(kicad_pcb
	(version 20260206)
	(generator "pcbnew")
	(generator_version "10.0")
	(general
		(thickness 1.6)
		(legacy_teardrops no)
	)
	(paper "A4")
	(title_block
		(title "04192023_DAF0TMB3IC0_F0TG_MB_C_brd_V02_OCP.brd")
		(comment 1 "Grand Teton / footprint 3955 of 8354 (U25), pads 3778-3888 of 6102")
	)
	(layers
		(0 "F.Cu" signal "TOP")
		(4 "In1.Cu" signal "GND")
		(6 "In2.Cu" signal "IN1")
		(8 "In3.Cu" signal "GND1")
		(10 "In4.Cu" signal "IN2")
		(12 "In5.Cu" signal "GND2")
		(14 "In6.Cu" signal "IN3")
		(16 "In7.Cu" signal "GND3")
		(18 "In8.Cu" signal "VCC")
		(20 "In9.Cu" signal "VCC1")
		(22 "In10.Cu" signal "GND4")
		(24 "In11.Cu" signal "IN4")
		(26 "In12.Cu" signal "GND5")
		(28 "In13.Cu" signal "IN5")
		(30 "In14.Cu" signal "GND6")
		(32 "In15.Cu" signal "IN6")
		(34 "In16.Cu" signal "GND7")
		(2 "B.Cu" signal "BOTTOM")
		(9 "F.Adhes" user "F.Adhesive")
		(11 "B.Adhes" user "B.Adhesive")
		(13 "F.Paste" user "Package Geometry/Pastemask Top")
		(15 "B.Paste" user "Package Geometry/Pastemask Bottom")
		(5 "F.SilkS" user "Ref Des/Silkscreen Top")
		(7 "B.SilkS" user "Ref Des/Silkscreen Bottom")
		(1 "F.Mask" user "Board Geometry/Soldermask Top")
		(3 "B.Mask" user "Board Geometry/Soldermask Bottom")
		(17 "Dwgs.User" user "User.Drawings")
		(19 "Cmts.User" user "User.Comments")
		(21 "Eco1.User" user "User.Eco1")
		(23 "Eco2.User" user "User.Eco2")
		(25 "Edge.Cuts" user "Board Geometry/Outline")
		(27 "Margin" user)
		(31 "F.CrtYd" user "Package Geometry/Place Bound Top")
		(29 "B.CrtYd" user "Package Geometry/Place Bound Bottom")
		(35 "F.Fab" user "Ref Des/Assembly Top")
		(33 "B.Fab" user "Ref Des/Assembly Bottom")
	)
	(footprint ""
		(layer "F.Cu")
		(at 359.867962 -258.880102 180)
		(property "Reference" "U25"
			(at -45.78477 -62.086744 0)
			(unlocked yes)
			(layer "F.SilkS")
			(effects
				(font
					(size 0.7874 0.5842)
					(thickness 0.1524)
				)
			)
		)
		(property "Value" ""
			(at 0 0 180)
			(layer "F.Fab")
			(effects
				(font
					(size 1.27 1.27)
				)
			)
		)
		(duplicate_pad_numbers_are_jumpers no)
		(pad "CP35" smd circle
			(at -2.970022 24.660098 180)
			(size 0.450088 0.450088)
			(layers "F.Cu" "F.Mask" "F.Paste")
			(net "P5E_CPU0_P2_RX_DP<1>")
		)
		(pad "CP36" smd circle
			(at -2.029968 24.660098 180)
			(size 0.450088 0.450088)
			(layers "F.Cu" "F.Mask" "F.Paste")
			(net "P5E_CPU0_P2_RX_DN<1>")
		)
		(pad "CP37" smd circle
			(at -1.089914 24.660098 180)
			(size 0.450088 0.450088)
			(layers "F.Cu" "F.Mask" "F.Paste")
			(net "GND")
		)
		(pad "CP39" smd circle
			(at 0.78994 24.660098 180)
			(size 0.450088 0.450088)
			(layers "F.Cu" "F.Mask" "F.Paste")
			(net "GND")
		)
		(pad "CP40" smd circle
			(at 1.729994 24.660098 180)
			(size 0.450088 0.450088)
			(layers "F.Cu" "F.Mask" "F.Paste")
			(net "P5E_CPU0_P0_TX_DN<14>")
		)
		(pad "CP41" smd circle
			(at 2.670048 24.660098 180)
			(size 0.450088 0.450088)
			(layers "F.Cu" "F.Mask" "F.Paste")
			(net "P5E_CPU0_P0_TX_DP<14>")
		)
		(pad "CP42" smd circle
			(at 3.610102 24.660098 180)
			(size 0.450088 0.450088)
			(layers "F.Cu" "F.Mask" "F.Paste")
			(net "GND")
		)
		(pad "CP43" smd circle
			(at 4.549902 24.660098 180)
			(size 0.450088 0.450088)
			(layers "F.Cu" "F.Mask" "F.Paste")
			(net "PVDDCR_CPU1_P0")
		)
		(pad "CP44" smd circle
			(at 5.489956 24.660098 180)
			(size 0.450088 0.450088)
			(layers "F.Cu" "F.Mask" "F.Paste")
			(net "PVDDCR_CPU1_P0")
		)
		(pad "CP45" smd circle
			(at 6.43001 24.660098 180)
			(size 0.450088 0.450088)
			(layers "F.Cu" "F.Mask" "F.Paste")
			(net "GND")
		)
		(pad "CP46" smd circle
			(at 7.370064 24.660098 180)
			(size 0.450088 0.450088)
			(layers "F.Cu" "F.Mask" "F.Paste")
			(net "PVDDCR_CPU1_P0")
		)
		(pad "CP47" smd circle
			(at 8.310118 24.660098 180)
			(size 0.450088 0.450088)
			(layers "F.Cu" "F.Mask" "F.Paste")
			(net "PVDDCR_CPU1_P0")
		)
		(pad "CP48" smd circle
			(at 9.249918 24.660098 180)
			(size 0.450088 0.450088)
			(layers "F.Cu" "F.Mask" "F.Paste")
			(net "GND")
		)
		(pad "CP49" smd circle
			(at 10.189972 24.660098 180)
			(size 0.450088 0.450088)
			(layers "F.Cu" "F.Mask" "F.Paste")
			(net "PVDDCR_CPU1_P0")
		)
		(pad "CP50" smd circle
			(at 11.130026 24.660098 180)
			(size 0.450088 0.450088)
			(layers "F.Cu" "F.Mask" "F.Paste")
			(net "PVDDCR_CPU1_P0")
		)
		(pad "CP51" smd circle
			(at 12.07008 24.660098 180)
			(size 0.450088 0.450088)
			(layers "F.Cu" "F.Mask" "F.Paste")
			(net "GND")
		)
		(pad "CP52" smd circle
			(at 13.00988 24.660098 180)
			(size 0.450088 0.450088)
			(layers "F.Cu" "F.Mask" "F.Paste")
			(net "PVDDCR_CPU1_P0")
		)
		(pad "CP53" smd circle
			(at 13.949934 24.660098 180)
			(size 0.450088 0.450088)
			(layers "F.Cu" "F.Mask" "F.Paste")
			(net "PVDDCR_CPU1_P0")
		)
		(pad "CP54" smd circle
			(at 14.889988 24.660098 180)
			(size 0.450088 0.450088)
			(layers "F.Cu" "F.Mask" "F.Paste")
			(net "GND")
		)
		(pad "CP55" smd circle
			(at 15.830042 24.660098 180)
			(size 0.450088 0.450088)
			(layers "F.Cu" "F.Mask" "F.Paste")
			(net "M_C_CPU0_SB_DQ<15>")
		)
		(pad "CP56" smd circle
			(at 16.770096 24.660098 180)
			(size 0.450088 0.450088)
			(layers "F.Cu" "F.Mask" "F.Paste")
			(net "M_C_CPU0_SB_DQ<16>")
		)
		(pad "CP57" smd circle
			(at 17.709896 24.660098 180)
			(size 0.450088 0.450088)
			(layers "F.Cu" "F.Mask" "F.Paste")
			(net "GND")
		)
		(pad "CP58" smd circle
			(at 18.64995 24.660098 180)
			(size 0.450088 0.450088)
			(layers "F.Cu" "F.Mask" "F.Paste")
			(net "M_D_CPU0_SB_DQ<15>")
		)
		(pad "CP59" smd circle
			(at 19.590004 24.660098 180)
			(size 0.450088 0.450088)
			(layers "F.Cu" "F.Mask" "F.Paste")
			(net "GND")
		)
		(pad "CP60" smd circle
			(at 20.530058 24.660098 180)
			(size 0.450088 0.450088)
			(layers "F.Cu" "F.Mask" "F.Paste")
			(net "M_D_CPU0_SB_DQ<16>")
		)
		(pad "CP61" smd circle
			(at 21.470112 24.660098 180)
			(size 0.450088 0.450088)
			(layers "F.Cu" "F.Mask" "F.Paste")
			(net "GND")
		)
		(pad "CP62" smd circle
			(at 22.409912 24.660098 180)
			(size 0.450088 0.450088)
			(layers "F.Cu" "F.Mask" "F.Paste")
			(net "M_B_CPU0_SB_DQ<15>")
		)
		(pad "CP63" smd circle
			(at 23.349966 24.660098 180)
			(size 0.450088 0.450088)
			(layers "F.Cu" "F.Mask" "F.Paste")
			(net "M_B_CPU0_SB_DQ<16>")
		)
		(pad "CP64" smd circle
			(at 24.29002 24.660098 180)
			(size 0.450088 0.450088)
			(layers "F.Cu" "F.Mask" "F.Paste")
			(net "GND")
		)
		(pad "CP65" smd circle
			(at 25.230074 24.660098 180)
			(size 0.450088 0.450088)
			(layers "F.Cu" "F.Mask" "F.Paste")
			(net "M_F_CPU0_SB_DQ<15>")
		)
		(pad "CP66" smd circle
			(at 26.170128 24.660098 180)
			(size 0.450088 0.450088)
			(layers "F.Cu" "F.Mask" "F.Paste")
			(net "GND")
		)
		(pad "CP67" smd circle
			(at 27.109928 24.660098 180)
			(size 0.450088 0.450088)
			(layers "F.Cu" "F.Mask" "F.Paste")
			(net "M_F_CPU0_SB_DQ<16>")
		)
		(pad "CP68" smd circle
			(at 28.049982 24.660098 180)
			(size 0.450088 0.450088)
			(layers "F.Cu" "F.Mask" "F.Paste")
			(net "GND")
		)
		(pad "CP69" smd circle
			(at 28.990036 24.660098 180)
			(size 0.450088 0.450088)
			(layers "F.Cu" "F.Mask" "F.Paste")
			(net "M_E_CPU0_SB_DQ<15>")
		)
		(pad "CP70" smd circle
			(at 29.93009 24.660098 180)
			(size 0.450088 0.450088)
			(layers "F.Cu" "F.Mask" "F.Paste")
			(net "M_E_CPU0_SB_DQ<16>")
		)
		(pad "CP71" smd circle
			(at 30.86989 24.660098 180)
			(size 0.450088 0.450088)
			(layers "F.Cu" "F.Mask" "F.Paste")
			(net "GND")
		)
		(pad "CP72" smd circle
			(at 31.809944 24.660098 180)
			(size 0.450088 0.450088)
			(layers "F.Cu" "F.Mask" "F.Paste")
			(net "M_A_CPU0_SB_DQ<15>")
		)
		(pad "CP73" smd circle
			(at 32.749998 24.660098 180)
			(size 0.450088 0.450088)
			(layers "F.Cu" "F.Mask" "F.Paste")
			(net "GND")
		)
		(pad "CP74" smd circle
			(at 33.690052 24.660098 180)
			(size 0.450088 0.450088)
			(layers "F.Cu" "F.Mask" "F.Paste")
			(net "M_A_CPU0_SB_DQ<16>")
		)
		(pad "CR1" smd circle
			(at -34.459926 25.470104 180)
			(size 0.450088 0.450088)
			(layers "F.Cu" "F.Mask" "F.Paste")
			(net "GND")
		)
		(pad "CR2" smd circle
			(at -33.519872 25.470104 180)
			(size 0.450088 0.450088)
			(layers "F.Cu" "F.Mask" "F.Paste")
			(net "M_G_CPU0_SB_DQ<18>")
		)
		(pad "CR3" smd circle
			(at -32.580072 25.470104 180)
			(size 0.450088 0.450088)
			(layers "F.Cu" "F.Mask" "F.Paste")
			(net "M_G_CPU0_SB_DQ<17>")
		)
		(pad "CR4" smd circle
			(at -31.640018 25.470104 180)
			(size 0.450088 0.450088)
			(layers "F.Cu" "F.Mask" "F.Paste")
			(net "GND")
		)
		(pad "CR5" smd circle
			(at -30.699964 25.470104 180)
			(size 0.450088 0.450088)
			(layers "F.Cu" "F.Mask" "F.Paste")
			(net "M_K_CPU0_SB_DQ<18>")
		)
		(pad "CR6" smd circle
			(at -29.75991 25.470104 180)
			(size 0.450088 0.450088)
			(layers "F.Cu" "F.Mask" "F.Paste")
			(net "GND")
		)
		(pad "CR7" smd circle
			(at -28.82011 25.470104 180)
			(size 0.450088 0.450088)
			(layers "F.Cu" "F.Mask" "F.Paste")
			(net "M_K_CPU0_SB_DQ<17>")
		)
		(pad "CR8" smd circle
			(at -27.880056 25.470104 180)
			(size 0.450088 0.450088)
			(layers "F.Cu" "F.Mask" "F.Paste")
			(net "GND")
		)
		(pad "CR9" smd circle
			(at -26.940002 25.470104 180)
			(size 0.450088 0.450088)
			(layers "F.Cu" "F.Mask" "F.Paste")
			(net "M_L_CPU0_SB_DQ<18>")
		)
		(pad "CR10" smd circle
			(at -25.999948 25.470104 180)
			(size 0.450088 0.450088)
			(layers "F.Cu" "F.Mask" "F.Paste")
			(net "M_L_CPU0_SB_DQ<17>")
		)
		(pad "CR11" smd circle
			(at -25.059894 25.470104 180)
			(size 0.450088 0.450088)
			(layers "F.Cu" "F.Mask" "F.Paste")
			(net "GND")
		)
		(pad "CR12" smd circle
			(at -24.120094 25.470104 180)
			(size 0.450088 0.450088)
			(layers "F.Cu" "F.Mask" "F.Paste")
			(net "M_H_CPU0_SB_DQ<18>")
		)
		(pad "CR13" smd circle
			(at -23.18004 25.470104 180)
			(size 0.450088 0.450088)
			(layers "F.Cu" "F.Mask" "F.Paste")
			(net "GND")
		)
		(pad "CR14" smd circle
			(at -22.239986 25.470104 180)
			(size 0.450088 0.450088)
			(layers "F.Cu" "F.Mask" "F.Paste")
			(net "M_H_CPU0_SB_DQ<17>")
		)
		(pad "CR15" smd circle
			(at -21.299932 25.470104 180)
			(size 0.450088 0.450088)
			(layers "F.Cu" "F.Mask" "F.Paste")
			(net "GND")
		)
		(pad "CR16" smd circle
			(at -20.359878 25.470104 180)
			(size 0.450088 0.450088)
			(layers "F.Cu" "F.Mask" "F.Paste")
			(net "M_J_CPU0_SB_DQ<18>")
		)
		(pad "CR17" smd circle
			(at -19.420078 25.470104 180)
			(size 0.450088 0.450088)
			(layers "F.Cu" "F.Mask" "F.Paste")
			(net "M_J_CPU0_SB_DQ<17>")
		)
		(pad "CR18" smd circle
			(at -18.480024 25.470104 180)
			(size 0.450088 0.450088)
			(layers "F.Cu" "F.Mask" "F.Paste")
			(net "GND")
		)
		(pad "CR19" smd circle
			(at -17.53997 25.470104 180)
			(size 0.450088 0.450088)
			(layers "F.Cu" "F.Mask" "F.Paste")
			(net "M_I_CPU0_SB_DQ<18>")
		)
		(pad "CR20" smd circle
			(at -16.599916 25.470104 180)
			(size 0.450088 0.450088)
			(layers "F.Cu" "F.Mask" "F.Paste")
			(net "GND")
		)
		(pad "CR21" smd circle
			(at -15.660116 25.470104 180)
			(size 0.450088 0.450088)
			(layers "F.Cu" "F.Mask" "F.Paste")
			(net "M_I_CPU0_SB_DQ<17>")
		)
		(pad "CR22" smd circle
			(at -14.720062 25.470104 180)
			(size 0.450088 0.450088)
			(layers "F.Cu" "F.Mask" "F.Paste")
			(net "GND")
		)
		(pad "CR23" smd circle
			(at -13.780008 25.470104 180)
			(size 0.450088 0.450088)
			(layers "F.Cu" "F.Mask" "F.Paste")
			(net "P5E_CPU0_P2_RX_DP<14>")
		)
		(pad "CR24" smd circle
			(at -12.839954 25.470104 180)
			(size 0.450088 0.450088)
			(layers "F.Cu" "F.Mask" "F.Paste")
			(net "P5E_CPU0_P2_RX_DN<14>")
		)
		(pad "CR25" smd circle
			(at -11.8999 25.470104 180)
			(size 0.450088 0.450088)
			(layers "F.Cu" "F.Mask" "F.Paste")
			(net "GND")
		)
		(pad "CR26" smd circle
			(at -10.9601 25.470104 180)
			(size 0.450088 0.450088)
			(layers "F.Cu" "F.Mask" "F.Paste")
			(net "P5E_CPU0_P2_RX_DP<11>")
		)
		(pad "CR27" smd circle
			(at -10.020046 25.470104 180)
			(size 0.450088 0.450088)
			(layers "F.Cu" "F.Mask" "F.Paste")
			(net "P5E_CPU0_P2_RX_DN<11>")
		)
		(pad "CR28" smd circle
			(at -9.079992 25.470104 180)
			(size 0.450088 0.450088)
			(layers "F.Cu" "F.Mask" "F.Paste")
			(net "GND")
		)
		(pad "CR29" smd circle
			(at -8.139938 25.470104 180)
			(size 0.450088 0.450088)
			(layers "F.Cu" "F.Mask" "F.Paste")
			(net "P5E_CPU0_P2_RX_DP<8>")
		)
		(pad "CR30" smd circle
			(at -7.199884 25.470104 180)
			(size 0.450088 0.450088)
			(layers "F.Cu" "F.Mask" "F.Paste")
			(net "P5E_CPU0_P2_RX_DN<8>")
		)
		(pad "CR31" smd circle
			(at -6.260084 25.470104 180)
			(size 0.450088 0.450088)
			(layers "F.Cu" "F.Mask" "F.Paste")
			(net "GND")
		)
		(pad "CR32" smd circle
			(at -5.32003 25.470104 180)
			(size 0.450088 0.450088)
			(layers "F.Cu" "F.Mask" "F.Paste")
			(net "P5E_CPU0_P2_RX_DP<5>")
		)
		(pad "CR33" smd circle
			(at -4.379976 25.470104 180)
			(size 0.450088 0.450088)
			(layers "F.Cu" "F.Mask" "F.Paste")
			(net "P5E_CPU0_P2_RX_DN<5>")
		)
		(pad "CR34" smd circle
			(at -3.439922 25.470104 180)
			(size 0.450088 0.450088)
			(layers "F.Cu" "F.Mask" "F.Paste")
			(net "GND")
		)
		(pad "CR35" smd circle
			(at -2.500122 25.470104 180)
			(size 0.450088 0.450088)
			(layers "F.Cu" "F.Mask" "F.Paste")
			(net "GND")
		)
		(pad "CR36" smd circle
			(at -1.560068 25.470104 180)
			(size 0.450088 0.450088)
			(layers "F.Cu" "F.Mask" "F.Paste")
			(net "GND")
		)
		(pad "CR40" smd circle
			(at 1.260094 25.470104 180)
			(size 0.450088 0.450088)
			(layers "F.Cu" "F.Mask" "F.Paste")
			(net "GND")
		)
		(pad "CR41" smd circle
			(at 2.199894 25.470104 180)
			(size 0.450088 0.450088)
			(layers "F.Cu" "F.Mask" "F.Paste")
			(net "GND")
		)
		(pad "CR42" smd circle
			(at 3.139948 25.470104 180)
			(size 0.450088 0.450088)
			(layers "F.Cu" "F.Mask" "F.Paste")
			(net "GND")
		)
		(pad "CR43" smd circle
			(at 4.080002 25.470104 180)
			(size 0.450088 0.450088)
			(layers "F.Cu" "F.Mask" "F.Paste")
			(net "P5E_CPU0_P0_TX_DN<10>")
		)
		(pad "CR44" smd circle
			(at 5.020056 25.470104 180)
			(size 0.450088 0.450088)
			(layers "F.Cu" "F.Mask" "F.Paste")
			(net "P5E_CPU0_P0_TX_DP<10>")
		)
		(pad "CR45" smd circle
			(at 5.96011 25.470104 180)
			(size 0.450088 0.450088)
			(layers "F.Cu" "F.Mask" "F.Paste")
			(net "GND")
		)
		(pad "CR46" smd circle
			(at 6.89991 25.470104 180)
			(size 0.450088 0.450088)
			(layers "F.Cu" "F.Mask" "F.Paste")
			(net "P5E_CPU0_P0_TX_DN<7>")
		)
		(pad "CR47" smd circle
			(at 7.839964 25.470104 180)
			(size 0.450088 0.450088)
			(layers "F.Cu" "F.Mask" "F.Paste")
			(net "P5E_CPU0_P0_TX_DP<7>")
		)
		(pad "CR48" smd circle
			(at 8.780018 25.470104 180)
			(size 0.450088 0.450088)
			(layers "F.Cu" "F.Mask" "F.Paste")
			(net "GND")
		)
		(pad "CR49" smd circle
			(at 9.720072 25.470104 180)
			(size 0.450088 0.450088)
			(layers "F.Cu" "F.Mask" "F.Paste")
			(net "P5E_CPU0_P0_TX_DN<4>")
		)
		(pad "CR50" smd circle
			(at 10.659872 25.470104 180)
			(size 0.450088 0.450088)
			(layers "F.Cu" "F.Mask" "F.Paste")
			(net "P5E_CPU0_P0_TX_DP<4>")
		)
		(pad "CR51" smd circle
			(at 11.599926 25.470104 180)
			(size 0.450088 0.450088)
			(layers "F.Cu" "F.Mask" "F.Paste")
			(net "GND")
		)
		(pad "CR52" smd circle
			(at 12.53998 25.470104 180)
			(size 0.450088 0.450088)
			(layers "F.Cu" "F.Mask" "F.Paste")
			(net "P5E_CPU0_P0_TX_DN<1>")
		)
		(pad "CR53" smd circle
			(at 13.480034 25.470104 180)
			(size 0.450088 0.450088)
			(layers "F.Cu" "F.Mask" "F.Paste")
			(net "P5E_CPU0_P0_TX_DP<1>")
		)
		(pad "CR54" smd circle
			(at 14.420088 25.470104 180)
			(size 0.450088 0.450088)
			(layers "F.Cu" "F.Mask" "F.Paste")
			(net "GND")
		)
		(pad "CR55" smd circle
			(at 15.359888 25.470104 180)
			(size 0.450088 0.450088)
			(layers "F.Cu" "F.Mask" "F.Paste")
			(net "M_C_CPU0_SB_DQ<17>")
		)
		(pad "CR56" smd circle
			(at 16.299942 25.470104 180)
			(size 0.450088 0.450088)
			(layers "F.Cu" "F.Mask" "F.Paste")
			(net "GND")
		)
		(pad "CR57" smd circle
			(at 17.239996 25.470104 180)
			(size 0.450088 0.450088)
			(layers "F.Cu" "F.Mask" "F.Paste")
			(net "M_C_CPU0_SB_DQ<18>")
		)
		(pad "CR58" smd circle
			(at 18.18005 25.470104 180)
			(size 0.450088 0.450088)
			(layers "F.Cu" "F.Mask" "F.Paste")
			(net "GND")
		)
		(pad "CR59" smd circle
			(at 19.120104 25.470104 180)
			(size 0.450088 0.450088)
			(layers "F.Cu" "F.Mask" "F.Paste")
			(net "M_D_CPU0_SB_DQ<17>")
		)
		(pad "CR60" smd circle
			(at 20.059904 25.470104 180)
			(size 0.450088 0.450088)
			(layers "F.Cu" "F.Mask" "F.Paste")
			(net "M_D_CPU0_SB_DQ<18>")
		)
		(pad "CR61" smd circle
			(at 20.999958 25.470104 180)
			(size 0.450088 0.450088)
			(layers "F.Cu" "F.Mask" "F.Paste")
			(net "GND")
		)
		(pad "CR62" smd circle
			(at 21.940012 25.470104 180)
			(size 0.450088 0.450088)
			(layers "F.Cu" "F.Mask" "F.Paste")
			(net "M_B_CPU0_SB_DQ<17>")
		)
		(pad "CR63" smd circle
			(at 22.880066 25.470104 180)
			(size 0.450088 0.450088)
			(layers "F.Cu" "F.Mask" "F.Paste")
			(net "GND")
		)
		(pad "CR64" smd circle
			(at 23.82012 25.470104 180)
			(size 0.450088 0.450088)
			(layers "F.Cu" "F.Mask" "F.Paste")
			(net "M_B_CPU0_SB_DQ<18>")
		)
		(pad "CR65" smd circle
			(at 24.75992 25.470104 180)
			(size 0.450088 0.450088)
			(layers "F.Cu" "F.Mask" "F.Paste")
			(net "GND")
		)
		(pad "CR66" smd circle
			(at 25.699974 25.470104 180)
			(size 0.450088 0.450088)
			(layers "F.Cu" "F.Mask" "F.Paste")
			(net "M_F_CPU0_SB_DQ<17>")
		)
		(pad "CR67" smd circle
			(at 26.640028 25.470104 180)
			(size 0.450088 0.450088)
			(layers "F.Cu" "F.Mask" "F.Paste")
			(net "M_F_CPU0_SB_DQ<18>")
		)
		(pad "CR68" smd circle
			(at 27.580082 25.470104 180)
			(size 0.450088 0.450088)
			(layers "F.Cu" "F.Mask" "F.Paste")
			(net "GND")
		)
		(pad "CR69" smd circle
			(at 28.519882 25.470104 180)
			(size 0.450088 0.450088)
			(layers "F.Cu" "F.Mask" "F.Paste")
			(net "M_E_CPU0_SB_DQ<17>")
		)
		(pad "CR70" smd circle
			(at 29.459936 25.470104 180)
			(size 0.450088 0.450088)
			(layers "F.Cu" "F.Mask" "F.Paste")
			(net "GND")
		)
		(pad "CR71" smd circle
			(at 30.39999 25.470104 180)
			(size 0.450088 0.450088)
			(layers "F.Cu" "F.Mask" "F.Paste")
			(net "M_E_CPU0_SB_DQ<18>")
		)
		(pad "CR72" smd circle
			(at 31.340044 25.470104 180)
			(size 0.450088 0.450088)
			(layers "F.Cu" "F.Mask" "F.Paste")
			(net "GND")
		)
		(pad "CR73" smd circle
			(at 32.280098 25.470104 180)
			(size 0.450088 0.450088)
			(layers "F.Cu" "F.Mask" "F.Paste")
			(net "M_A_CPU0_SB_DQ<17>")
		)
		(pad "CR74" smd circle
			(at 33.219898 25.470104 180)
			(size 0.450088 0.450088)
			(layers "F.Cu" "F.Mask" "F.Paste")
			(net "M_A_CPU0_SB_DQ<18>")
		)
		(pad "CR75" smd circle
			(at 34.159952 25.470104 180)
			(size 0.450088 0.450088)
			(layers "F.Cu" "F.Mask" "F.Paste")
			(net "GND")
		)
	)
)
